# T6G (Grand Teton) — schematic netlist excerpt (pin names and nets, part order shuffled) for the footprints in the layout excerpt that follows; sources: Cadence DE-HDL packaged netlist, KiCad conversion of 04192023_DAF0TMB3IC0_F0TG_MB_C_brd_V02_OCP.brd

C2291  Q_CAP  22UF 4V 20% X6S  pkg C0402  page 72 : A = PVDD11_S3_P1 ; B = GND
R2415  Q_RES  33.2 1% CHIP  pkg 0402LF  page 150 : A = SMB_1_BMC_GPU_SCL ; B = SMB_PCIE3_3V3AUX_SCL_R

(kicad_pcb
	(version 20260206)
	(generator "pcbnew")
	(generator_version "10.0")
	(general
		(thickness 1.6)
		(legacy_teardrops no)
	)
	(paper "A4")
	(title_block
		(title "04192023_DAF0TMB3IC0_F0TG_MB_C_brd_V02_OCP.brd")
		(comment 1 "Grand Teton / footprints 7098-7099 of 8354")
	)
	(layers
		(0 "F.Cu" signal "TOP")
		(4 "In1.Cu" signal "GND")
		(6 "In2.Cu" signal "IN1")
		(8 "In3.Cu" signal "GND1")
		(10 "In4.Cu" signal "IN2")
		(12 "In5.Cu" signal "GND2")
		(14 "In6.Cu" signal "IN3")
		(16 "In7.Cu" signal "GND3")
		(18 "In8.Cu" signal "VCC")
		(20 "In9.Cu" signal "VCC1")
		(22 "In10.Cu" signal "GND4")
		(24 "In11.Cu" signal "IN4")
		(26 "In12.Cu" signal "GND5")
		(28 "In13.Cu" signal "IN5")
		(30 "In14.Cu" signal "GND6")
		(32 "In15.Cu" signal "IN6")
		(34 "In16.Cu" signal "GND7")
		(2 "B.Cu" signal "BOTTOM")
		(9 "F.Adhes" user "F.Adhesive")
		(11 "B.Adhes" user "B.Adhesive")
		(13 "F.Paste" user "Package Geometry/Pastemask Top")
		(15 "B.Paste" user "Package Geometry/Pastemask Bottom")
		(5 "F.SilkS" user "Ref Des/Silkscreen Top")
		(7 "B.SilkS" user "Ref Des/Silkscreen Bottom")
		(1 "F.Mask" user "Board Geometry/Soldermask Top")
		(3 "B.Mask" user "Board Geometry/Soldermask Bottom")
		(17 "Dwgs.User" user "User.Drawings")
		(19 "Cmts.User" user "User.Comments")
		(21 "Eco1.User" user "User.Eco1")
		(23 "Eco2.User" user "User.Eco2")
		(25 "Edge.Cuts" user "Board Geometry/Outline")
		(27 "Margin" user)
		(31 "F.CrtYd" user "Package Geometry/Place Bound Top")
		(29 "B.CrtYd" user "Package Geometry/Place Bound Bottom")
		(35 "F.Fab" user "Ref Des/Assembly Top")
		(33 "B.Fab" user "Ref Des/Assembly Bottom")
	)
	(footprint ""
		(layer "B.Cu")
		(at 154.00782 -13.762228 90)
		(property "Reference" "R2415"
			(at 0 0 90)
			(layer "B.SilkS")
			(hide yes)
			(effects
				(font
					(size 1.27 1.27)
				)
				(justify mirror)
			)
		)
		(property "Value" ""
			(at 0 0 90)
			(layer "B.Fab")
			(effects
				(font
					(size 1.27 1.27)
				)
				(justify mirror)
			)
		)
		(duplicate_pad_numbers_are_jumpers no)
		(fp_line
			(start 0.7874 -0.4064)
			(end -0.7874 -0.4064)
			(stroke
				(width 0.1524)
				(type default)
			)
			(layer "B.SilkS")
		)
		(fp_line
			(start -0.7874 -0.4064)
			(end -0.7874 0.4064)
			(stroke
				(width 0.1524)
				(type default)
			)
			(layer "B.SilkS")
		)
		(fp_line
			(start 0.7874 0.4064)
			(end 0.7874 -0.4064)
			(stroke
				(width 0.1524)
				(type default)
			)
			(layer "B.SilkS")
		)
		(fp_line
			(start -0.7874 0.4064)
			(end 0.7874 0.4064)
			(stroke
				(width 0.1524)
				(type default)
			)
			(layer "B.SilkS")
		)
		(fp_line
			(start 0.67945 -0.305054)
			(end 0.12065 -0.305054)
			(stroke
				(width 0.1)
				(type default)
			)
			(layer "B.Fab")
		)
		(fp_line
			(start 0.12065 -0.305054)
			(end 0.12065 -0.2794)
			(stroke
				(width 0.1)
				(type default)
			)
			(layer "B.Fab")
		)
		(fp_line
			(start -0.12065 -0.3048)
			(end -0.67945 -0.3048)
			(stroke
				(width 0.1)
				(type default)
			)
			(layer "B.Fab")
		)
		(fp_line
			(start -0.67945 -0.3048)
			(end -0.67945 0.3048)
			(stroke
				(width 0.1)
				(type default)
			)
			(layer "B.Fab")
		)
		(fp_line
			(start 0.12065 -0.2794)
			(end -0.12065 -0.2794)
			(stroke
				(width 0.1)
				(type default)
			)
			(layer "B.Fab")
		)
		(fp_line
			(start -0.12065 -0.2794)
			(end -0.12065 -0.3048)
			(stroke
				(width 0.1)
				(type default)
			)
			(layer "B.Fab")
		)
		(fp_line
			(start 0.12065 0.2794)
			(end 0.12065 0.3048)
			(stroke
				(width 0.1)
				(type default)
			)
			(layer "B.Fab")
		)
		(fp_line
			(start -0.120396 0.2794)
			(end 0.12065 0.2794)
			(stroke
				(width 0.1)
				(type default)
			)
			(layer "B.Fab")
		)
		(fp_line
			(start 0.67945 0.3048)
			(end 0.67945 -0.305054)
			(stroke
				(width 0.1)
				(type default)
			)
			(layer "B.Fab")
		)
		(fp_line
			(start 0.12065 0.3048)
			(end 0.67945 0.3048)
			(stroke
				(width 0.1)
				(type default)
			)
			(layer "B.Fab")
		)
		(fp_line
			(start -0.120396 0.3048)
			(end -0.120396 0.2794)
			(stroke
				(width 0.1)
				(type default)
			)
			(layer "B.Fab")
		)
		(fp_line
			(start -0.67945 0.3048)
			(end -0.120396 0.3048)
			(stroke
				(width 0.1)
				(type default)
			)
			(layer "B.Fab")
		)
		(pad "1" smd circle
			(at 0.40005 0 270)
			(size 0 0)
			(layers "B.Cu" "B.Mask" "B.Paste")
			(net "SMB_1_BMC_GPU_SCL")
		)
		(pad "2" smd circle
			(at -0.40005 0 270)
			(size 0 0)
			(layers "B.Cu" "B.Mask" "B.Paste")
			(net "SMB_PCIE3_3V3AUX_SCL_R")
		)
	)
	(footprint ""
		(layer "B.Cu")
		(at 111.477044 -261.748016 90)
		(property "Reference" "C2291"
			(at 0 0 90)
			(layer "B.SilkS")
			(hide yes)
			(effects
				(font
					(size 1.27 1.27)
				)
				(justify mirror)
			)
		)
		(property "Value" ""
			(at 0 0 90)
			(layer "B.Fab")
			(effects
				(font
					(size 1.27 1.27)
				)
				(justify mirror)
			)
		)
		(duplicate_pad_numbers_are_jumpers no)
		(fp_line
			(start 0.7874 -0.4064)
			(end -0.7874 -0.4064)
			(stroke
				(width 0.1524)
				(type default)
			)
			(layer "B.SilkS")
		)
		(fp_line
			(start -0.7874 -0.4064)
			(end -0.7874 0.4064)
			(stroke
				(width 0.1524)
				(type default)
			)
			(layer "B.SilkS")
		)
		(fp_line
			(start 0.7874 0.4064)
			(end 0.7874 -0.4064)
			(stroke
				(width 0.1524)
				(type default)
			)
			(layer "B.SilkS")
		)
		(fp_line
			(start -0.7874 0.4064)
			(end 0.7874 0.4064)
			(stroke
				(width 0.1524)
				(type default)
			)
			(layer "B.SilkS")
		)
		(fp_line
			(start 0.67945 -0.305054)
			(end 0.12065 -0.305054)
			(stroke
				(width 0.1)
				(type default)
			)
			(layer "B.Fab")
		)
		(fp_line
			(start 0.12065 -0.305054)
			(end 0.12065 -0.2794)
			(stroke
				(width 0.1)
				(type default)
			)
			(layer "B.Fab")
		)
		(fp_line
			(start -0.12065 -0.3048)
			(end -0.67945 -0.3048)
			(stroke
				(width 0.1)
				(type default)
			)
			(layer "B.Fab")
		)
		(fp_line
			(start -0.67945 -0.3048)
			(end -0.67945 0.3048)
			(stroke
				(width 0.1)
				(type default)
			)
			(layer "B.Fab")
		)
		(fp_line
			(start 0.12065 -0.2794)
			(end -0.12065 -0.2794)
			(stroke
				(width 0.1)
				(type default)
			)
			(layer "B.Fab")
		)
		(fp_line
			(start -0.12065 -0.2794)
			(end -0.12065 -0.3048)
			(stroke
				(width 0.1)
				(type default)
			)
			(layer "B.Fab")
		)
		(fp_line
			(start 0.12065 0.2794)
			(end 0.12065 0.3048)
			(stroke
				(width 0.1)
				(type default)
			)
			(layer "B.Fab")
		)
		(fp_line
			(start -0.120396 0.2794)
			(end 0.12065 0.2794)
			(stroke
				(width 0.1)
				(type default)
			)
			(layer "B.Fab")
		)
		(fp_line
			(start 0.67945 0.3048)
			(end 0.67945 -0.305054)
			(stroke
				(width 0.1)
				(type default)
			)
			(layer "B.Fab")
		)
		(fp_line
			(start 0.12065 0.3048)
			(end 0.67945 0.3048)
			(stroke
				(width 0.1)
				(type default)
			)
			(layer "B.Fab")
		)
		(fp_line
			(start -0.120396 0.3048)
			(end -0.120396 0.2794)
			(stroke
				(width 0.1)
				(type default)
			)
			(layer "B.Fab")
		)
		(fp_line
			(start -0.67945 0.3048)
			(end -0.120396 0.3048)
			(stroke
				(width 0.1)
				(type default)
			)
			(layer "B.Fab")
		)
		(pad "1" smd circle
			(at 0.40005 0 270)
			(size 0 0)
			(layers "B.Cu" "B.Mask" "B.Paste")
			(net "PVDD11_S3_P1")
		)
		(pad "2" smd circle
			(at -0.40005 0 270)
			(size 0 0)
			(layers "B.Cu" "B.Mask" "B.Paste")
			(net "GND")
		)
	)
)
